FILE_TYPE = MULTI_PHYS_TABLE;
PART 'TTL2G07'
{========================================================================================================================================================================================}
:VALUE|PACK_TYPE|MATERIAL|PART_NUMBER= EnvComp |PART_NUMBER|JEDEC_TYPE|DESCRIPTION|CLASS|COMPONENT_TYPE|HEIGHT|LPID  | SPEED_URL | Status |RPL| AML | Bus_Unit | Days ;
{========================================================================================================================================================================================}
'74LVC2G07' | 'SOT23LF' | 'IC'     | 'D22707-001'(!) = 'YES;YES;UNK;UNK;ok;VLD' | 'D22707-001' | 'SOT23_6A' | 'DUAL BUFFER/DRIVER WITH OPEN-DRAIN OUTPUT' | 'IC'  | 'SMALLSMT'     | '0.057 IN' | '354' | 'http://speed.intel.com:8081/speed/module/pdm/item/pdm_item_detail_direct.asp?item_cde=D22707-001&item_rev=01&url_param=unused' | 'Conditional' | 'YES' | '3' | 'SMO_IC' | '91' 
'74LVC2G07' | 'SOT23LF' | 'EMPTY'  | 'D22707-001'(!) = 'YES;YES;UNK;UNK;ok;VLD' | 'D22707-001' | 'SOT23_6A' | 'DUAL BUFFER/DRIVER WITH OPEN-DRAIN OUTPUT' | 'IO'  | 'SMALLSMT'     | '0.057 IN' | '354' | 'http://speed.intel.com:8081/speed/module/pdm/item/pdm_item_detail_direct.asp?item_cde=D22707-001&item_rev=01&url_param=unused' | 'Conditional' | 'YES' | '3' | 'SMO_IC' | '91' 
END_PART
END.
